(kicad_pcb
	(version 20241229)
	(generator "pcbnew")
	(generator_version "9.0")
	(general
		(thickness 1.294)
		(legacy_teardrops no)
	)
	(paper "A3")
	(title_block
		(title "Kintex 410T devboard")
		(date "2024-04-03")
		(rev "1.1.2")
		(comment 9 "footprint 89 of 975 (J18), pads 534-564 of 564")
	)
	(layers
		(0 "F.Cu" mixed)
		(4 "In1.Cu" power)
		(6 "In2.Cu" power)
		(8 "In3.Cu" mixed)
		(10 "In4.Cu" power)
		(12 "In5.Cu" mixed)
		(14 "In6.Cu" power)
		(16 "In7.Cu" mixed)
		(18 "In8.Cu" power)
		(2 "B.Cu" mixed)
		(9 "F.Adhes" user "F.Adhesive")
		(11 "B.Adhes" user "B.Adhesive")
		(13 "F.Paste" user)
		(15 "B.Paste" user)
		(5 "F.SilkS" user "F.Silkscreen")
		(7 "B.SilkS" user "B.Silkscreen")
		(1 "F.Mask" user)
		(3 "B.Mask" user)
		(17 "Dwgs.User" user "User.Drawings")
		(19 "Cmts.User" user "User.Comments")
		(21 "Eco1.User" user "User.Eco1")
		(23 "Eco2.User" user "User.Eco2")
		(25 "Edge.Cuts" user)
		(27 "Margin" user)
		(31 "F.CrtYd" user "F.Courtyard")
		(29 "B.CrtYd" user "B.Courtyard")
		(35 "F.Fab" user)
		(33 "B.Fab" user)
	)
	(footprint "antmicro-footprints:ASP-184329-01_mounting_holes"
		(layer "F.Cu")
		(at 162.000001 106.000001 90)
		(property "Reference" "J18"
			(at 28.280001 4.299999 180)
			(layer "F.SilkS")
			(effects
				(font
					(size 0.7 0.7)
					(thickness 0.15)
				)
				(justify left bottom)
			)
		)
		(property "Value" "ASP-184329-01_mounting_holes"
			(at -8.4 0.2 90)
			(layer "F.Fab")
			(effects
				(font
					(size 0.7 0.7)
					(thickness 0.15)
				)
				(justify left bottom)
			)
		)
		(property "Description" "Mezzanine Connector, Array, Female, 1.27 mm, 14 Rows, 560 Contacts, Surface Mount"
			(at 0 0 90)
			(layer "F.Fab")
			(hide yes)
			(effects
				(font
					(size 1.27 1.27)
					(thickness 0.15)
				)
			)
		)
		(property "Author" "Antmicro"
			(at 268.000002 -56 0)
			(layer "F.Fab")
			(hide yes)
			(effects
				(font
					(size 1 1)
					(thickness 0.15)
				)
			)
		)
		(property "License" "Apache-2.0"
			(at 268.000002 -56 0)
			(layer "F.Fab")
			(hide yes)
			(effects
				(font
					(size 1 1)
					(thickness 0.15)
				)
			)
		)
		(property "MPN" "ASP-184329-01"
			(at 268.000002 -56 0)
			(layer "F.Fab")
			(hide yes)
			(effects
				(font
					(size 1 1)
					(thickness 0.15)
				)
			)
		)
		(property "Manufacturer" "Samtec"
			(at 268.000002 -56 0)
			(layer "F.Fab")
			(hide yes)
			(effects
				(font
					(size 1 1)
					(thickness 0.15)
				)
			)
		)
		(sheetname "FMC+ HSPC")
		(sheetfile "fmc-hspc.kicad_sch")
		(attr smd)
		(pad "Z10" smd circle
			(at 13.335 6.985 90)
			(size 0.64 0.64)
			(layers "F.Cu" "F.Mask")
			(net 1 "GND")
			(pinfunction "GND")
			(pintype "passive")
		)
		(pad "Z11" smd circle
			(at 12.063 6.985 90)
			(size 0.64 0.64)
			(layers "F.Cu" "F.Mask")
			(net 1 "GND")
			(pinfunction "GND")
			(pintype "passive")
		)
		(pad "Z12" smd circle
			(at 10.794 6.985 90)
			(size 0.64 0.64)
			(layers "F.Cu" "F.Mask")
			(net 313 "unconnected-(J18H-DP11_M2C_P-PadZ12)")
			(pinfunction "DP11_M2C_P")
			(pintype "passive+no_connect")
		)
		(pad "Z13" smd circle
			(at 9.525 6.985 90)
			(size 0.64 0.64)
			(layers "F.Cu" "F.Mask")
			(net 314 "unconnected-(J18H-DP11_M2C_N-PadZ13)")
			(pinfunction "DP11_M2C_N")
			(pintype "passive+no_connect")
		)
		(pad "Z14" smd circle
			(at 8.255 6.985 90)
			(size 0.64 0.64)
			(layers "F.Cu" "F.Mask")
			(net 1 "GND")
			(pinfunction "GND")
			(pintype "passive")
		)
		(pad "Z15" smd circle
			(at 6.985 6.985 90)
			(size 0.64 0.64)
			(layers "F.Cu" "F.Mask")
			(net 1 "GND")
			(pinfunction "GND")
			(pintype "passive")
		)
		(pad "Z16" smd circle
			(at 5.714 6.985 90)
			(size 0.64 0.64)
			(layers "F.Cu" "F.Mask")
			(net 315 "unconnected-(J18H-DP13_M2C_P-PadZ16)")
			(pinfunction "DP13_M2C_P")
			(pintype "passive+no_connect")
		)
		(pad "Z17" smd circle
			(at 4.445 6.985 90)
			(size 0.64 0.64)
			(layers "F.Cu" "F.Mask")
			(net 316 "unconnected-(J18H-DP13_M2C_N-PadZ17)")
			(pinfunction "DP13_M2C_N")
			(pintype "passive+no_connect")
		)
		(pad "Z18" smd circle
			(at 3.173 6.985 90)
			(size 0.64 0.64)
			(layers "F.Cu" "F.Mask")
			(net 1 "GND")
			(pinfunction "GND")
			(pintype "passive")
		)
		(pad "Z19" smd circle
			(at 1.904 6.985 90)
			(size 0.64 0.64)
			(layers "F.Cu" "F.Mask")
			(net 1 "GND")
			(pinfunction "GND")
			(pintype "passive")
		)
		(pad "Z20" smd circle
			(at 0.633 6.985 90)
			(size 0.64 0.64)
			(layers "F.Cu" "F.Mask")
			(net 317 "unconnected-(J18G-GBTCLK5_M2C_P-PadZ20)")
			(pinfunction "GBTCLK5_M2C_P")
			(pintype "passive+no_connect")
		)
		(pad "Z21" smd circle
			(at -0.635 6.985 90)
			(size 0.64 0.64)
			(layers "F.Cu" "F.Mask")
			(net 318 "unconnected-(J18G-GBTCLK5_M2C_N-PadZ21)")
			(pinfunction "GBTCLK5_M2C_N")
			(pintype "passive+no_connect")
		)
		(pad "Z22" smd circle
			(at -1.905 6.985 90)
			(size 0.64 0.64)
			(layers "F.Cu" "F.Mask")
			(net 1 "GND")
			(pinfunction "GND")
			(pintype "passive")
		)
		(pad "Z23" smd circle
			(at -3.176 6.985 90)
			(size 0.64 0.64)
			(layers "F.Cu" "F.Mask")
			(net 1 "GND")
			(pinfunction "GND")
			(pintype "passive")
		)
		(pad "Z24" smd circle
			(at -4.446 6.985 90)
			(size 0.64 0.64)
			(layers "F.Cu" "F.Mask")
			(net 319 "unconnected-(J18H-DP10_C2M_P-PadZ24)")
			(pinfunction "DP10_C2M_P")
			(pintype "passive+no_connect")
		)
		(pad "Z25" smd circle
			(at -5.715 6.985 90)
			(size 0.64 0.64)
			(layers "F.Cu" "F.Mask")
			(net 320 "unconnected-(J18H-DP10_C2M_N-PadZ25)")
			(pinfunction "DP10_C2M_N")
			(pintype "passive+no_connect")
		)
		(pad "Z26" smd circle
			(at -6.986 6.985 90)
			(size 0.64 0.64)
			(layers "F.Cu" "F.Mask")
			(net 1 "GND")
			(pinfunction "GND")
			(pintype "passive")
		)
		(pad "Z27" smd circle
			(at -8.257 6.985 90)
			(size 0.64 0.64)
			(layers "F.Cu" "F.Mask")
			(net 1 "GND")
			(pinfunction "GND")
			(pintype "passive")
		)
		(pad "Z28" smd circle
			(at -9.526 6.985 90)
			(size 0.64 0.64)
			(layers "F.Cu" "F.Mask")
			(net 321 "unconnected-(J18H-DP12_C2M_P-PadZ28)")
			(pinfunction "DP12_C2M_P")
			(pintype "passive+no_connect")
		)
		(pad "Z29" smd circle
			(at -10.795 6.985 90)
			(size 0.64 0.64)
			(layers "F.Cu" "F.Mask")
			(net 322 "unconnected-(J18H-DP12_C2M_N-PadZ29)")
			(pinfunction "DP12_C2M_N")
			(pintype "passive+no_connect")
		)
		(pad "Z30" smd circle
			(at -12.065 6.985 90)
			(size 0.64 0.64)
			(layers "F.Cu" "F.Mask")
			(net 1 "GND")
			(pinfunction "GND")
			(pintype "passive")
		)
		(pad "Z31" smd circle
			(at -13.337 6.985 90)
			(size 0.64 0.64)
			(layers "F.Cu" "F.Mask")
			(net 1 "GND")
			(pinfunction "GND")
			(pintype "passive")
		)
		(pad "Z32" smd circle
			(at -14.606 6.985 90)
			(size 0.64 0.64)
			(layers "F.Cu" "F.Mask")
			(net 323 "unconnected-(J18H-DP16_M2C_P-PadZ32)")
			(pinfunction "DP16_M2C_P")
			(pintype "passive+no_connect")
		)
		(pad "Z33" smd circle
			(at -15.875 6.985 90)
			(size 0.64 0.64)
			(layers "F.Cu" "F.Mask")
			(net 324 "unconnected-(J18H-DP16_M2C_N-PadZ33)")
			(pinfunction "DP16_M2C_N")
			(pintype "passive+no_connect")
		)
		(pad "Z34" smd circle
			(at -17.145 6.985 90)
			(size 0.64 0.64)
			(layers "F.Cu" "F.Mask")
			(net 1 "GND")
			(pinfunction "GND")
			(pintype "passive")
		)
		(pad "Z35" smd circle
			(at -18.415 6.985 90)
			(size 0.64 0.64)
			(layers "F.Cu" "F.Mask")
			(net 1 "GND")
			(pinfunction "GND")
			(pintype "passive")
		)
		(pad "Z36" smd circle
			(at -19.685 6.985 90)
			(size 0.64 0.64)
			(layers "F.Cu" "F.Mask")
			(net 325 "unconnected-(J18H-DP18_M2C_P-PadZ36)")
			(pinfunction "DP18_M2C_P")
			(pintype "passive+no_connect")
		)
		(pad "Z37" smd circle
			(at -20.956 6.985 90)
			(size 0.64 0.64)
			(layers "F.Cu" "F.Mask")
			(net 326 "unconnected-(J18H-DP18_M2C_N-PadZ37)")
			(pinfunction "DP18_M2C_N")
			(pintype "passive+no_connect")
		)
		(pad "Z38" smd circle
			(at -22.226 6.985 90)
			(size 0.64 0.64)
			(layers "F.Cu" "F.Mask")
			(net 1 "GND")
			(pinfunction "GND")
			(pintype "passive")
		)
		(pad "Z39" smd circle
			(at -23.497 6.985 90)
			(size 0.64 0.64)
			(layers "F.Cu" "F.Mask")
			(net 1 "GND")
			(pinfunction "GND")
			(pintype "passive")
		)
		(pad "Z40" smd circle
			(at -24.767 6.985 90)
			(size 0.64 0.64)
			(layers "F.Cu" "F.Mask")
			(net 24 "+3V3")
			(pinfunction "3P3V")
			(pintype "passive")
		)
	)
)
